# T6G (Grand Teton) — schematic netlist excerpt (pin names and nets, part order shuffled) for the footprints in the layout excerpt that follows; sources: Cadence DE-HDL packaged netlist, KiCad conversion of 04192023_DAF0TMB3IC0_F0TG_MB_C_brd_V02_OCP.brd

C746  Q_CAP_DIFFBUS  DIFF BUS_0.22UF 6.3V 20% X6S  pkg C0201  page 66 : \1\ = P5E_CPU1_P2_TX_C_DN<13> ; \2\ = P5E_CPU1_P2_TX_DN<13>
C6090  Q_CAP  27PF 50V 5% NPO  pkg 0402  page 179 : A = XTAL_USB_CPU0_HUB2_XOUT ; B = GND
PC6523  Q_CAP  22UF 16V 20% X6S  pkg C0805  page 361 : A = SW_P12V_AUX_P1V8_RETIMER_CPU1_FLT ; B = GND

(kicad_pcb
	(version 20260206)
	(generator "pcbnew")
	(generator_version "10.0")
	(general
		(thickness 1.6)
		(legacy_teardrops no)
	)
	(paper "A4")
	(title_block
		(title "04192023_DAF0TMB3IC0_F0TG_MB_C_brd_V02_OCP.brd")
		(comment 1 "Grand Teton / footprints 527-529 of 8354")
	)
	(layers
		(0 "F.Cu" signal "TOP")
		(4 "In1.Cu" signal "GND")
		(6 "In2.Cu" signal "IN1")
		(8 "In3.Cu" signal "GND1")
		(10 "In4.Cu" signal "IN2")
		(12 "In5.Cu" signal "GND2")
		(14 "In6.Cu" signal "IN3")
		(16 "In7.Cu" signal "GND3")
		(18 "In8.Cu" signal "VCC")
		(20 "In9.Cu" signal "VCC1")
		(22 "In10.Cu" signal "GND4")
		(24 "In11.Cu" signal "IN4")
		(26 "In12.Cu" signal "GND5")
		(28 "In13.Cu" signal "IN5")
		(30 "In14.Cu" signal "GND6")
		(32 "In15.Cu" signal "IN6")
		(34 "In16.Cu" signal "GND7")
		(2 "B.Cu" signal "BOTTOM")
		(9 "F.Adhes" user "F.Adhesive")
		(11 "B.Adhes" user "B.Adhesive")
		(13 "F.Paste" user "Package Geometry/Pastemask Top")
		(15 "B.Paste" user "Package Geometry/Pastemask Bottom")
		(5 "F.SilkS" user "Ref Des/Silkscreen Top")
		(7 "B.SilkS" user "Ref Des/Silkscreen Bottom")
		(1 "F.Mask" user "Board Geometry/Soldermask Top")
		(3 "B.Mask" user "Board Geometry/Soldermask Bottom")
		(17 "Dwgs.User" user "User.Drawings")
		(19 "Cmts.User" user "User.Comments")
		(21 "Eco1.User" user "User.Eco1")
		(23 "Eco2.User" user "User.Eco2")
		(25 "Edge.Cuts" user "Board Geometry/Outline")
		(27 "Margin" user)
		(31 "F.CrtYd" user "Package Geometry/Place Bound Top")
		(29 "B.CrtYd" user "Package Geometry/Place Bound Bottom")
		(35 "F.Fab" user "Ref Des/Assembly Top")
		(33 "B.Fab" user "Ref Des/Assembly Bottom")
	)
	(footprint ""
		(layer "F.Cu")
		(at 105.334054 -25.183592 180)
		(property "Reference" "C6090"
			(at 0 0 180)
			(layer "F.SilkS")
			(hide yes)
			(effects
				(font
					(size 1.27 1.27)
				)
			)
		)
		(property "Value" ""
			(at 0 0 180)
			(layer "F.Fab")
			(effects
				(font
					(size 1.27 1.27)
				)
			)
		)
		(duplicate_pad_numbers_are_jumpers no)
		(fp_line
			(start 0.7874 0.4064)
			(end -0.7874 0.4064)
			(stroke
				(width 0.1524)
				(type default)
			)
			(layer "F.SilkS")
		)
		(fp_line
			(start 0.7874 -0.4064)
			(end 0.7874 0.4064)
			(stroke
				(width 0.1524)
				(type default)
			)
			(layer "F.SilkS")
		)
		(fp_line
			(start -0.7874 0.4064)
			(end -0.7874 -0.4064)
			(stroke
				(width 0.1524)
				(type default)
			)
			(layer "F.SilkS")
		)
		(fp_line
			(start -0.7874 -0.4064)
			(end 0.7874 -0.4064)
			(stroke
				(width 0.1524)
				(type default)
			)
			(layer "F.SilkS")
		)
		(fp_line
			(start 0.67945 0.3048)
			(end 0.120396 0.3048)
			(stroke
				(width 0.1)
				(type default)
			)
			(layer "F.Fab")
		)
		(fp_line
			(start 0.67945 -0.3048)
			(end 0.67945 0.3048)
			(stroke
				(width 0.1)
				(type default)
			)
			(layer "F.Fab")
		)
		(fp_line
			(start 0.12065 -0.2794)
			(end 0.12065 -0.3048)
			(stroke
				(width 0.1)
				(type default)
			)
			(layer "F.Fab")
		)
		(fp_line
			(start 0.12065 -0.3048)
			(end 0.67945 -0.3048)
			(stroke
				(width 0.1)
				(type default)
			)
			(layer "F.Fab")
		)
		(fp_line
			(start 0.120396 0.3048)
			(end 0.120396 0.2794)
			(stroke
				(width 0.1)
				(type default)
			)
			(layer "F.Fab")
		)
		(fp_line
			(start 0.120396 0.2794)
			(end -0.12065 0.2794)
			(stroke
				(width 0.1)
				(type default)
			)
			(layer "F.Fab")
		)
		(fp_line
			(start -0.12065 0.3048)
			(end -0.67945 0.3048)
			(stroke
				(width 0.1)
				(type default)
			)
			(layer "F.Fab")
		)
		(fp_line
			(start -0.12065 0.2794)
			(end -0.12065 0.3048)
			(stroke
				(width 0.1)
				(type default)
			)
			(layer "F.Fab")
		)
		(fp_line
			(start -0.12065 -0.2794)
			(end 0.12065 -0.2794)
			(stroke
				(width 0.1)
				(type default)
			)
			(layer "F.Fab")
		)
		(fp_line
			(start -0.12065 -0.305054)
			(end -0.12065 -0.2794)
			(stroke
				(width 0.1)
				(type default)
			)
			(layer "F.Fab")
		)
		(fp_line
			(start -0.67945 0.3048)
			(end -0.67945 -0.305054)
			(stroke
				(width 0.1)
				(type default)
			)
			(layer "F.Fab")
		)
		(fp_line
			(start -0.67945 -0.305054)
			(end -0.12065 -0.305054)
			(stroke
				(width 0.1)
				(type default)
			)
			(layer "F.Fab")
		)
		(pad "1" smd circle
			(at -0.40005 0 180)
			(size 0 0)
			(layers "F.Cu" "F.Mask" "F.Paste")
			(net "XTAL_USB_CPU0_HUB2_XOUT")
		)
		(pad "2" smd circle
			(at 0.40005 0 180)
			(size 0 0)
			(layers "F.Cu" "F.Mask" "F.Paste")
			(net "GND")
		)
	)
	(footprint ""
		(layer "F.Cu")
		(at 169.058844 -370.57203 -90)
		(property "Reference" "C746"
			(at 0 0 270)
			(layer "F.SilkS")
			(hide yes)
			(effects
				(font
					(size 1.27 1.27)
				)
			)
		)
		(property "Value" ""
			(at 0 0 270)
			(layer "F.Fab")
			(effects
				(font
					(size 1.27 1.27)
				)
			)
		)
		(duplicate_pad_numbers_are_jumpers no)
		(fp_line
			(start -0.299974 0.150114)
			(end -0.299974 -0.150114)
			(stroke
				(width 0.1)
				(type default)
			)
			(layer "F.Fab")
		)
		(fp_line
			(start 0.299974 0.150114)
			(end -0.299974 0.150114)
			(stroke
				(width 0.1)
				(type default)
			)
			(layer "F.Fab")
		)
		(fp_line
			(start -0.299974 -0.150114)
			(end 0.299974 -0.150114)
			(stroke
				(width 0.1)
				(type default)
			)
			(layer "F.Fab")
		)
		(fp_line
			(start 0.299974 -0.150114)
			(end 0.299974 0.150114)
			(stroke
				(width 0.1)
				(type default)
			)
			(layer "F.Fab")
		)
		(pad "1" smd rect
			(at -0.2667 0 270)
			(size 0.3048 0.381)
			(layers "F.Cu" "F.Mask" "F.Paste")
			(net "P5E_CPU1_P2_TX_C_DN<13>")
		)
		(pad "2" smd rect
			(at 0.2667 0 270)
			(size 0.3048 0.381)
			(layers "F.Cu" "F.Mask" "F.Paste")
			(net "P5E_CPU1_P2_TX_DN<13>")
		)
	)
	(footprint ""
		(layer "F.Cu")
		(at 229.87 -282.188666 180)
		(property "Reference" "PC6523"
			(at 0 0 180)
			(layer "F.SilkS")
			(hide yes)
			(effects
				(font
					(size 1.27 1.27)
				)
			)
		)
		(property "Value" ""
			(at 0 0 180)
			(layer "F.Fab")
			(effects
				(font
					(size 1.27 1.27)
				)
			)
		)
		(duplicate_pad_numbers_are_jumpers no)
		(fp_line
			(start 1.524 0.762)
			(end -1.524 0.762)
			(stroke
				(width 0.1524)
				(type default)
			)
			(layer "F.SilkS")
		)
		(fp_line
			(start 1.524 -0.762)
			(end 1.524 0.762)
			(stroke
				(width 0.1524)
				(type default)
			)
			(layer "F.SilkS")
		)
		(fp_line
			(start -1.524 0.762)
			(end -1.524 -0.762)
			(stroke
				(width 0.1524)
				(type default)
			)
			(layer "F.SilkS")
		)
		(fp_line
			(start -1.524 -0.762)
			(end 1.524 -0.762)
			(stroke
				(width 0.1524)
				(type default)
			)
			(layer "F.SilkS")
		)
		(fp_line
			(start 1.1049 0.724916)
			(end 1.1049 -0.724916)
			(stroke
				(width 0.1)
				(type default)
			)
			(layer "F.Fab")
		)
		(fp_line
			(start 1.1049 -0.724916)
			(end -1.1049 -0.724916)
			(stroke
				(width 0.1)
				(type default)
			)
			(layer "F.Fab")
		)
		(fp_line
			(start -1.1049 0.724916)
			(end 1.1049 0.724916)
			(stroke
				(width 0.1)
				(type default)
			)
			(layer "F.Fab")
		)
		(fp_line
			(start -1.1049 -0.724916)
			(end -1.1049 0.724916)
			(stroke
				(width 0.1)
				(type default)
			)
			(layer "F.Fab")
		)
		(pad "1" smd rect
			(at -0.889 0)
			(size 1.016 1.27)
			(layers "F.Cu" "F.Mask" "F.Paste")
			(net "SW_P12V_AUX_P1V8_RETIMER_CPU1_FLT")
		)
		(pad "2" smd rect
			(at 0.889 0)
			(size 1.016 1.27)
			(layers "F.Cu" "F.Mask" "F.Paste")
			(net "GND")
		)
	)
)
